(kicad_pcb
	(version 20260206)
	(generator "pcbnew")
	(generator_version "10.0")
	(general
		(thickness 1.6)
		(legacy_teardrops no)
	)
	(paper "A4")
	(title_block
		(title "01162023_DA0F0TEBIF0_F0T_Expander_BD_F_brd_V02_OCP.brd")
		(comment 1 "Grand Teton / footprints 5439-5444 of 9728")
	)
	(layers
		(0 "F.Cu" signal "TOP")
		(4 "In1.Cu" signal "GND")
		(6 "In2.Cu" signal "VCC")
		(8 "In3.Cu" signal "VCC1")
		(10 "In4.Cu" signal "GND1")
		(12 "In5.Cu" signal "IN1")
		(14 "In6.Cu" signal "GND2")
		(16 "In7.Cu" signal "IN2")
		(18 "In8.Cu" signal "GND3")
		(20 "In9.Cu" signal "IN3")
		(22 "In10.Cu" signal "GND4")
		(24 "In11.Cu" signal "IN4")
		(26 "In12.Cu" signal "GND5")
		(28 "In13.Cu" signal "IN5")
		(30 "In14.Cu" signal "GND6")
		(32 "In15.Cu" signal "IN6")
		(34 "In16.Cu" signal "GND7")
		(2 "B.Cu" signal "BOTTOM")
		(9 "F.Adhes" user "F.Adhesive")
		(11 "B.Adhes" user "B.Adhesive")
		(13 "F.Paste" user "Package Geometry/Pastemask Top")
		(15 "B.Paste" user "Package Geometry/Pastemask Bottom")
		(5 "F.SilkS" user "Ref Des/Silkscreen Top")
		(7 "B.SilkS" user "Ref Des/Silkscreen Bottom")
		(1 "F.Mask" user "Board Geometry/Soldermask Top")
		(3 "B.Mask" user "Board Geometry/Soldermask Bottom")
		(17 "Dwgs.User" user "User.Drawings")
		(19 "Cmts.User" user "User.Comments")
		(21 "Eco1.User" user "User.Eco1")
		(23 "Eco2.User" user "User.Eco2")
		(25 "Edge.Cuts" user "Board Geometry/Outline")
		(27 "Margin" user)
		(31 "F.CrtYd" user "Package Geometry/Place Bound Top")
		(29 "B.CrtYd" user "Package Geometry/Place Bound Bottom")
		(35 "F.Fab" user "Ref Des/Assembly Top")
		(33 "B.Fab" user "Ref Des/Assembly Bottom")
	)
	(footprint ""
		(layer "F.Cu")
		(at 361.188 -193.294)
		(property "Reference" "R4638"
			(at 0 0 0)
			(layer "F.SilkS")
			(hide yes)
			(effects
				(font
					(size 1.27 1.27)
				)
			)
		)
		(property "Value" ""
			(at 0 0 0)
			(layer "F.Fab")
			(effects
				(font
					(size 1.27 1.27)
				)
			)
		)
		(duplicate_pad_numbers_are_jumpers no)
		(fp_line
			(start -0.7874 -0.4064)
			(end 0.7874 -0.4064)
			(stroke
				(width 0.1524)
				(type default)
			)
			(layer "F.SilkS")
		)
		(fp_line
			(start -0.7874 0.4064)
			(end -0.7874 -0.4064)
			(stroke
				(width 0.1524)
				(type default)
			)
			(layer "F.SilkS")
		)
		(fp_line
			(start 0.7874 -0.4064)
			(end 0.7874 0.4064)
			(stroke
				(width 0.1524)
				(type default)
			)
			(layer "F.SilkS")
		)
		(fp_line
			(start 0.7874 0.4064)
			(end -0.7874 0.4064)
			(stroke
				(width 0.1524)
				(type default)
			)
			(layer "F.SilkS")
		)
		(fp_line
			(start -0.67945 -0.305054)
			(end -0.12065 -0.305054)
			(stroke
				(width 0.1)
				(type default)
			)
			(layer "F.Fab")
		)
		(fp_line
			(start -0.67945 0.3048)
			(end -0.67945 -0.305054)
			(stroke
				(width 0.1)
				(type default)
			)
			(layer "F.Fab")
		)
		(fp_line
			(start -0.12065 -0.305054)
			(end -0.12065 -0.2794)
			(stroke
				(width 0.1)
				(type default)
			)
			(layer "F.Fab")
		)
		(fp_line
			(start -0.12065 -0.2794)
			(end 0.12065 -0.2794)
			(stroke
				(width 0.1)
				(type default)
			)
			(layer "F.Fab")
		)
		(fp_line
			(start -0.12065 0.2794)
			(end -0.12065 0.3048)
			(stroke
				(width 0.1)
				(type default)
			)
			(layer "F.Fab")
		)
		(fp_line
			(start -0.12065 0.3048)
			(end -0.67945 0.3048)
			(stroke
				(width 0.1)
				(type default)
			)
			(layer "F.Fab")
		)
		(fp_line
			(start 0.120396 0.2794)
			(end -0.12065 0.2794)
			(stroke
				(width 0.1)
				(type default)
			)
			(layer "F.Fab")
		)
		(fp_line
			(start 0.120396 0.3048)
			(end 0.120396 0.2794)
			(stroke
				(width 0.1)
				(type default)
			)
			(layer "F.Fab")
		)
		(fp_line
			(start 0.12065 -0.3048)
			(end 0.67945 -0.3048)
			(stroke
				(width 0.1)
				(type default)
			)
			(layer "F.Fab")
		)
		(fp_line
			(start 0.12065 -0.2794)
			(end 0.12065 -0.3048)
			(stroke
				(width 0.1)
				(type default)
			)
			(layer "F.Fab")
		)
		(fp_line
			(start 0.67945 -0.3048)
			(end 0.67945 0.3048)
			(stroke
				(width 0.1)
				(type default)
			)
			(layer "F.Fab")
		)
		(fp_line
			(start 0.67945 0.3048)
			(end 0.120396 0.3048)
			(stroke
				(width 0.1)
				(type default)
			)
			(layer "F.Fab")
		)
		(pad "1" smd circle
			(at -0.40005 0)
			(size 0 0)
			(layers "F.Cu" "F.Mask" "F.Paste")
			(net "PEX0_PCA9555_1_INT_N")
		)
		(pad "2" smd circle
			(at 0.40005 0)
			(size 0 0)
			(layers "F.Cu" "F.Mask" "F.Paste")
			(net "P1V8_PEX")
		)
	)
	(footprint ""
		(layer "F.Cu")
		(at 58.176922 -375.524268 180)
		(property "Reference" "R1822"
			(at 0 0 180)
			(layer "F.SilkS")
			(hide yes)
			(effects
				(font
					(size 1.27 1.27)
				)
			)
		)
		(property "Value" ""
			(at 0 0 180)
			(layer "F.Fab")
			(effects
				(font
					(size 1.27 1.27)
				)
			)
		)
		(duplicate_pad_numbers_are_jumpers no)
		(fp_line
			(start 0.7874 0.4064)
			(end -0.7874 0.4064)
			(stroke
				(width 0.1524)
				(type default)
			)
			(layer "F.SilkS")
		)
		(fp_line
			(start 0.7874 -0.4064)
			(end 0.7874 0.4064)
			(stroke
				(width 0.1524)
				(type default)
			)
			(layer "F.SilkS")
		)
		(fp_line
			(start -0.7874 0.4064)
			(end -0.7874 -0.4064)
			(stroke
				(width 0.1524)
				(type default)
			)
			(layer "F.SilkS")
		)
		(fp_line
			(start -0.7874 -0.4064)
			(end 0.7874 -0.4064)
			(stroke
				(width 0.1524)
				(type default)
			)
			(layer "F.SilkS")
		)
		(fp_line
			(start 0.67945 0.3048)
			(end 0.120396 0.3048)
			(stroke
				(width 0.1)
				(type default)
			)
			(layer "F.Fab")
		)
		(fp_line
			(start 0.67945 -0.3048)
			(end 0.67945 0.3048)
			(stroke
				(width 0.1)
				(type default)
			)
			(layer "F.Fab")
		)
		(fp_line
			(start 0.12065 -0.2794)
			(end 0.12065 -0.3048)
			(stroke
				(width 0.1)
				(type default)
			)
			(layer "F.Fab")
		)
		(fp_line
			(start 0.12065 -0.3048)
			(end 0.67945 -0.3048)
			(stroke
				(width 0.1)
				(type default)
			)
			(layer "F.Fab")
		)
		(fp_line
			(start 0.120396 0.3048)
			(end 0.120396 0.2794)
			(stroke
				(width 0.1)
				(type default)
			)
			(layer "F.Fab")
		)
		(fp_line
			(start 0.120396 0.2794)
			(end -0.12065 0.2794)
			(stroke
				(width 0.1)
				(type default)
			)
			(layer "F.Fab")
		)
		(fp_line
			(start -0.12065 0.3048)
			(end -0.67945 0.3048)
			(stroke
				(width 0.1)
				(type default)
			)
			(layer "F.Fab")
		)
		(fp_line
			(start -0.12065 0.2794)
			(end -0.12065 0.3048)
			(stroke
				(width 0.1)
				(type default)
			)
			(layer "F.Fab")
		)
		(fp_line
			(start -0.12065 -0.2794)
			(end 0.12065 -0.2794)
			(stroke
				(width 0.1)
				(type default)
			)
			(layer "F.Fab")
		)
		(fp_line
			(start -0.12065 -0.305054)
			(end -0.12065 -0.2794)
			(stroke
				(width 0.1)
				(type default)
			)
			(layer "F.Fab")
		)
		(fp_line
			(start -0.67945 0.3048)
			(end -0.67945 -0.305054)
			(stroke
				(width 0.1)
				(type default)
			)
			(layer "F.Fab")
		)
		(fp_line
			(start -0.67945 -0.305054)
			(end -0.12065 -0.305054)
			(stroke
				(width 0.1)
				(type default)
			)
			(layer "F.Fab")
		)
		(pad "1" smd circle
			(at -0.40005 0 180)
			(size 0 0)
			(layers "F.Cu" "F.Mask" "F.Paste")
			(net "PRSNT_GPU_D_R_N")
		)
		(pad "2" smd circle
			(at 0.40005 0 180)
			(size 0 0)
			(layers "F.Cu" "F.Mask" "F.Paste")
			(net "PRSNT_GPU_D_N")
		)
	)
	(footprint ""
		(layer "F.Cu")
		(at 358.043226 -396.80769 180)
		(property "Reference" "R6702"
			(at 0 0 180)
			(layer "F.SilkS")
			(hide yes)
			(effects
				(font
					(size 1.27 1.27)
				)
			)
		)
		(property "Value" ""
			(at 0 0 180)
			(layer "F.Fab")
			(effects
				(font
					(size 1.27 1.27)
				)
			)
		)
		(duplicate_pad_numbers_are_jumpers no)
		(fp_line
			(start 0.7874 0.4064)
			(end -0.7874 0.4064)
			(stroke
				(width 0.1524)
				(type default)
			)
			(layer "F.SilkS")
		)
		(fp_line
			(start 0.7874 -0.4064)
			(end 0.7874 0.4064)
			(stroke
				(width 0.1524)
				(type default)
			)
			(layer "F.SilkS")
		)
		(fp_line
			(start -0.7874 0.4064)
			(end -0.7874 -0.4064)
			(stroke
				(width 0.1524)
				(type default)
			)
			(layer "F.SilkS")
		)
		(fp_line
			(start -0.7874 -0.4064)
			(end 0.7874 -0.4064)
			(stroke
				(width 0.1524)
				(type default)
			)
			(layer "F.SilkS")
		)
		(fp_line
			(start 0.67945 0.3048)
			(end 0.120396 0.3048)
			(stroke
				(width 0.1)
				(type default)
			)
			(layer "F.Fab")
		)
		(fp_line
			(start 0.67945 -0.3048)
			(end 0.67945 0.3048)
			(stroke
				(width 0.1)
				(type default)
			)
			(layer "F.Fab")
		)
		(fp_line
			(start 0.12065 -0.2794)
			(end 0.12065 -0.3048)
			(stroke
				(width 0.1)
				(type default)
			)
			(layer "F.Fab")
		)
		(fp_line
			(start 0.12065 -0.3048)
			(end 0.67945 -0.3048)
			(stroke
				(width 0.1)
				(type default)
			)
			(layer "F.Fab")
		)
		(fp_line
			(start 0.120396 0.3048)
			(end 0.120396 0.2794)
			(stroke
				(width 0.1)
				(type default)
			)
			(layer "F.Fab")
		)
		(fp_line
			(start 0.120396 0.2794)
			(end -0.12065 0.2794)
			(stroke
				(width 0.1)
				(type default)
			)
			(layer "F.Fab")
		)
		(fp_line
			(start -0.12065 0.3048)
			(end -0.67945 0.3048)
			(stroke
				(width 0.1)
				(type default)
			)
			(layer "F.Fab")
		)
		(fp_line
			(start -0.12065 0.2794)
			(end -0.12065 0.3048)
			(stroke
				(width 0.1)
				(type default)
			)
			(layer "F.Fab")
		)
		(fp_line
			(start -0.12065 -0.2794)
			(end 0.12065 -0.2794)
			(stroke
				(width 0.1)
				(type default)
			)
			(layer "F.Fab")
		)
		(fp_line
			(start -0.12065 -0.305054)
			(end -0.12065 -0.2794)
			(stroke
				(width 0.1)
				(type default)
			)
			(layer "F.Fab")
		)
		(fp_line
			(start -0.67945 0.3048)
			(end -0.67945 -0.305054)
			(stroke
				(width 0.1)
				(type default)
			)
			(layer "F.Fab")
		)
		(fp_line
			(start -0.67945 -0.305054)
			(end -0.12065 -0.305054)
			(stroke
				(width 0.1)
				(type default)
			)
			(layer "F.Fab")
		)
		(pad "1" smd circle
			(at -0.40005 0 180)
			(size 0 0)
			(layers "F.Cu" "F.Mask" "F.Paste")
			(net "MB_3V3IO_RSVD3_N")
		)
		(pad "2" smd circle
			(at 0.40005 0 180)
			(size 0 0)
			(layers "F.Cu" "F.Mask" "F.Paste")
			(net "P3V3_AUX")
		)
	)
	(footprint ""
		(layer "F.Cu")
		(at 46.575472 -69.47916 180)
		(property "Reference" "PU75"
			(at -2.224786 -3.080004 90)
			(unlocked yes)
			(layer "F.SilkS")
			(effects
				(font
					(size 0.7874 0.5842)
					(thickness 0.1524)
				)
			)
		)
		(property "Value" ""
			(at 0 0 180)
			(layer "F.Fab")
			(effects
				(font
					(size 1.27 1.27)
				)
			)
		)
		(duplicate_pad_numbers_are_jumpers no)
		(fp_line
			(start 1.239774 1.495298)
			(end -1.239774 1.495298)
			(stroke
				(width 0.1524)
				(type default)
			)
			(layer "F.SilkS")
		)
		(fp_line
			(start 1.239774 -1.495298)
			(end 1.239774 1.495298)
			(stroke
				(width 0.1524)
				(type default)
			)
			(layer "F.SilkS")
		)
		(fp_line
			(start -1.239774 1.495298)
			(end -1.239774 -1.495298)
			(stroke
				(width 0.1524)
				(type default)
			)
			(layer "F.SilkS")
		)
		(fp_line
			(start -1.239774 -1.495298)
			(end 1.239774 -1.495298)
			(stroke
				(width 0.1524)
				(type default)
			)
			(layer "F.SilkS")
		)
		(fp_poly
			(pts
				(xy -1.718056 -1.180084) (xy -2.436622 -0.461518) (xy -1.3589 -0.102362)
			)
			(stroke
				(width 0)
				(type default)
			)
			(fill yes)
			(layer "F.SilkS")
		)
		(fp_line
			(start 0.8001 1.050036)
			(end -0.8001 1.050036)
			(stroke
				(width 0.1)
				(type default)
			)
			(layer "F.Fab")
		)
		(fp_line
			(start 0.8001 -1.050036)
			(end 0.8001 1.050036)
			(stroke
				(width 0.1)
				(type default)
			)
			(layer "F.Fab")
		)
		(fp_line
			(start -0.8001 1.050036)
			(end -0.8001 -1.050036)
			(stroke
				(width 0.1)
				(type default)
			)
			(layer "F.Fab")
		)
		(fp_line
			(start -0.8001 -1.050036)
			(end 0.8001 -1.050036)
			(stroke
				(width 0.1)
				(type default)
			)
			(layer "F.Fab")
		)
		(fp_poly
			(pts
				(xy -2.458974 -0.508) (xy -2.458974 0.508) (xy -1.442974 0)
			)
			(stroke
				(width 0)
				(type default)
			)
			(fill yes)
			(layer "F.Fab")
		)
		(pad "1_2" smd circle
			(at -0.374904 0 270)
			(size 0 0)
			(layers "F.Cu" "F.Mask" "F.Paste")
			(net "P12V_AUX")
		)
		(pad "3" smd rect
			(at -0.499872 0.999998 180)
			(size 0.254 0.7112)
			(layers "F.Cu" "F.Mask" "F.Paste")
			(net "GND")
		)
		(pad "4" smd rect
			(at 0 0.999998 180)
			(size 0.254 0.7112)
			(layers "F.Cu" "F.Mask" "F.Paste")
			(net "P12V_SSD1_CO_ILIMIT")
		)
		(pad "5" smd rect
			(at 0.499872 0.999998 180)
			(size 0.254 0.7112)
			(layers "F.Cu" "F.Mask" "F.Paste")
			(net "P12V_SSD1_CO_MODE")
		)
		(pad "6_7" smd circle
			(at 0.374904 0 90)
			(size 0 0)
			(layers "F.Cu" "F.Mask" "F.Paste")
			(net "P12V_SSD1_R")
		)
		(pad "8" smd rect
			(at 0.499872 -0.999998 180)
			(size 0.254 0.7112)
			(layers "F.Cu" "F.Mask" "F.Paste")
			(net "P12V_SSD1_CO_GATE")
		)
		(pad "9" smd rect
			(at 0 -0.999998 180)
			(size 0.254 0.7112)
			(layers "F.Cu" "F.Mask" "F.Paste")
			(net "P12V_SSD1_CO_EN")
		)
		(pad "10" smd rect
			(at -0.499872 -0.999998 180)
			(size 0.254 0.7112)
			(layers "F.Cu" "F.Mask" "F.Paste")
			(net "P12V_SSD1_CO_DV_DT")
		)
	)
	(footprint ""
		(layer "F.Cu")
		(at 188.22543 -42.849038 180)
		(property "Reference" "R579"
			(at 0 0 180)
			(layer "F.SilkS")
			(hide yes)
			(effects
				(font
					(size 1.27 1.27)
				)
			)
		)
		(property "Value" ""
			(at 0 0 180)
			(layer "F.Fab")
			(effects
				(font
					(size 1.27 1.27)
				)
			)
		)
		(duplicate_pad_numbers_are_jumpers no)
		(fp_line
			(start 0.7874 0.4064)
			(end -0.7874 0.4064)
			(stroke
				(width 0.1524)
				(type default)
			)
			(layer "F.SilkS")
		)
		(fp_line
			(start 0.7874 -0.4064)
			(end 0.7874 0.4064)
			(stroke
				(width 0.1524)
				(type default)
			)
			(layer "F.SilkS")
		)
		(fp_line
			(start -0.7874 0.4064)
			(end -0.7874 -0.4064)
			(stroke
				(width 0.1524)
				(type default)
			)
			(layer "F.SilkS")
		)
		(fp_line
			(start -0.7874 -0.4064)
			(end 0.7874 -0.4064)
			(stroke
				(width 0.1524)
				(type default)
			)
			(layer "F.SilkS")
		)
		(fp_line
			(start 0.67945 0.3048)
			(end 0.120396 0.3048)
			(stroke
				(width 0.1)
				(type default)
			)
			(layer "F.Fab")
		)
		(fp_line
			(start 0.67945 -0.3048)
			(end 0.67945 0.3048)
			(stroke
				(width 0.1)
				(type default)
			)
			(layer "F.Fab")
		)
		(fp_line
			(start 0.12065 -0.2794)
			(end 0.12065 -0.3048)
			(stroke
				(width 0.1)
				(type default)
			)
			(layer "F.Fab")
		)
		(fp_line
			(start 0.12065 -0.3048)
			(end 0.67945 -0.3048)
			(stroke
				(width 0.1)
				(type default)
			)
			(layer "F.Fab")
		)
		(fp_line
			(start 0.120396 0.3048)
			(end 0.120396 0.2794)
			(stroke
				(width 0.1)
				(type default)
			)
			(layer "F.Fab")
		)
		(fp_line
			(start 0.120396 0.2794)
			(end -0.12065 0.2794)
			(stroke
				(width 0.1)
				(type default)
			)
			(layer "F.Fab")
		)
		(fp_line
			(start -0.12065 0.3048)
			(end -0.67945 0.3048)
			(stroke
				(width 0.1)
				(type default)
			)
			(layer "F.Fab")
		)
		(fp_line
			(start -0.12065 0.2794)
			(end -0.12065 0.3048)
			(stroke
				(width 0.1)
				(type default)
			)
			(layer "F.Fab")
		)
		(fp_line
			(start -0.12065 -0.2794)
			(end 0.12065 -0.2794)
			(stroke
				(width 0.1)
				(type default)
			)
			(layer "F.Fab")
		)
		(fp_line
			(start -0.12065 -0.305054)
			(end -0.12065 -0.2794)
			(stroke
				(width 0.1)
				(type default)
			)
			(layer "F.Fab")
		)
		(fp_line
			(start -0.67945 0.3048)
			(end -0.67945 -0.305054)
			(stroke
				(width 0.1)
				(type default)
			)
			(layer "F.Fab")
		)
		(fp_line
			(start -0.67945 -0.305054)
			(end -0.12065 -0.305054)
			(stroke
				(width 0.1)
				(type default)
			)
			(layer "F.Fab")
		)
		(pad "1" smd circle
			(at -0.40005 0 180)
			(size 0 0)
			(layers "F.Cu" "F.Mask" "F.Paste")
			(net "P12V_SSD6_R")
		)
		(pad "2" smd circle
			(at 0.40005 0 180)
			(size 0 0)
			(layers "F.Cu" "F.Mask" "F.Paste")
			(net "P12V_SSD6_VIN_P")
		)
	)
	(footprint ""
		(layer "F.Cu")
		(at 411.825948 -165.670484 -90)
		(property "Reference" "R3311"
			(at 0 0 270)
			(layer "F.SilkS")
			(hide yes)
			(effects
				(font
					(size 1.27 1.27)
				)
			)
		)
		(property "Value" ""
			(at 0 0 270)
			(layer "F.Fab")
			(effects
				(font
					(size 1.27 1.27)
				)
			)
		)
		(duplicate_pad_numbers_are_jumpers no)
		(fp_line
			(start -0.7874 0.4064)
			(end -0.7874 -0.4064)
			(stroke
				(width 0.1524)
				(type default)
			)
			(layer "F.SilkS")
		)
		(fp_line
			(start 0.7874 0.4064)
			(end -0.7874 0.4064)
			(stroke
				(width 0.1524)
				(type default)
			)
			(layer "F.SilkS")
		)
		(fp_line
			(start -0.7874 -0.4064)
			(end 0.7874 -0.4064)
			(stroke
				(width 0.1524)
				(type default)
			)
			(layer "F.SilkS")
		)
		(fp_line
			(start 0.7874 -0.4064)
			(end 0.7874 0.4064)
			(stroke
				(width 0.1524)
				(type default)
			)
			(layer "F.SilkS")
		)
		(fp_line
			(start -0.67945 0.3048)
			(end -0.67945 -0.305054)
			(stroke
				(width 0.1)
				(type default)
			)
			(layer "F.Fab")
		)
		(fp_line
			(start -0.12065 0.3048)
			(end -0.67945 0.3048)
			(stroke
				(width 0.1)
				(type default)
			)
			(layer "F.Fab")
		)
		(fp_line
			(start 0.120396 0.3048)
			(end 0.120396 0.2794)
			(stroke
				(width 0.1)
				(type default)
			)
			(layer "F.Fab")
		)
		(fp_line
			(start 0.67945 0.3048)
			(end 0.120396 0.3048)
			(stroke
				(width 0.1)
				(type default)
			)
			(layer "F.Fab")
		)
		(fp_line
			(start -0.12065 0.2794)
			(end -0.12065 0.3048)
			(stroke
				(width 0.1)
				(type default)
			)
			(layer "F.Fab")
		)
		(fp_line
			(start 0.120396 0.2794)
			(end -0.12065 0.2794)
			(stroke
				(width 0.1)
				(type default)
			)
			(layer "F.Fab")
		)
		(fp_line
			(start -0.12065 -0.2794)
			(end 0.12065 -0.2794)
			(stroke
				(width 0.1)
				(type default)
			)
			(layer "F.Fab")
		)
		(fp_line
			(start 0.12065 -0.2794)
			(end 0.12065 -0.3048)
			(stroke
				(width 0.1)
				(type default)
			)
			(layer "F.Fab")
		)
		(fp_line
			(start 0.12065 -0.3048)
			(end 0.67945 -0.3048)
			(stroke
				(width 0.1)
				(type default)
			)
			(layer "F.Fab")
		)
		(fp_line
			(start 0.67945 -0.3048)
			(end 0.67945 0.3048)
			(stroke
				(width 0.1)
				(type default)
			)
			(layer "F.Fab")
		)
		(fp_line
			(start -0.67945 -0.305054)
			(end -0.12065 -0.305054)
			(stroke
				(width 0.1)
				(type default)
			)
			(layer "F.Fab")
		)
		(fp_line
			(start -0.12065 -0.305054)
			(end -0.12065 -0.2794)
			(stroke
				(width 0.1)
				(type default)
			)
			(layer "F.Fab")
		)
		(pad "1" smd circle
			(at -0.40005 0 270)
			(size 0 0)
			(layers "F.Cu" "F.Mask" "F.Paste")
			(net "FM_SYS_THROTTLE_R")
		)
		(pad "2" smd circle
			(at 0.40005 0 270)
			(size 0 0)
			(layers "F.Cu" "F.Mask" "F.Paste")
			(net "FM_SYS_THROTTLE_NIC7")
		)
	)
)
